FILE_TYPE = CONNECTIVITY;
{Allegro Design Entry HDL 17.2-2016 S081 (4005846) 1/11/2022}
"PAGE_NUMBER" = 131;
0"NC";
1"P3V3_AUX\g";
2"P3V3_AUX\g";
3"P3V3_AUX\g";
4"P3V3_AUX\g";
5"P12V_AUX\g";
6"P3V3_AUX\g";
7"P3V3_AUX\g";
8"P12V_AUX\g";
9"P12V_AUX\g";
10"P3V3_AUX\g";
11"P12V_OCP_V3_2\g";
12"P3V3_AUX\g";
13"P3V3_OCP_V3_2_R\g";
14"GND\g";
15"GND\g";
16"GND\g";
17"GND\g";
18"GND\g";
19"GND\g";
20"GND\g";
21"GND\g";
22"GND\g";
23"GND\g";
24"GND\g";
25"GND\g";
26"GND\g";
27"GND\g";
28"GND\g";
29"GND\g";
30"GND\g";
31"GND\g";
32"GND\g";
33"GND\g";
34"GND\g";
35"GND\g";
36"GND\g";
37"P12V_OCP_SENSE_2";
38"P12V_OCP_FAULT_2";
39"P12V_OCP_PWRGD_2";
40"P12V_OCP_CB_2";
41"P12V_OCP_OV_2";
42"P12V_OCP_REG_2";
43"P12V_OCP_VCC_2";
44"P3V3_OCP_REG_2";
45"P3V3_OCP_VCC_2";
46"P3V3_OCP_PWRGD_2";
47"P3V3_OCP_FAULT_2";
48"P3V3_OCP_GATE_2";
49"P12V_OCP_GATE_2";
50"P12V_OCP_V3_2_ISENSE_MAM_TIC";
51"HP_LVC3_OCP_V3_2_ATTN_OUT_SW_N"CDS_PHYS_NET_NAME"HP_LVC3_OCP_V3_2_ATTN_OUT_SW_N";
52"HP_LVC3_OCP_V3_2_P12V_PWRGD";
53"OCP_V3_2_P3V3_PWRGD";
54"P3V3_OCP_SENSE_2";
55"P3V3_OCP_CB_2";
56"P3V3_OCP_OV_2";
57"P12V_OCP_V3_2_ISENSE_MAM_MAM";
58"HP_LVC3_OCP_V3_2_PRSNT2_PLD_N"CDS_PHYS_NET_NAME"HP_LVC3_OCP_V3_2_PRSNT2_PLD_N";
59"HP_LVC3_OCP_V3_2_PRSNT2_N"CDS_PHYS_NET_NAME"HP_LVC3_OCP_V3_2_PRSNT2_N";
60"HP_LVC3_OCP_V3_2_PRSNT2_N_R"CDS_PHYS_NET_NAME"HP_LVC3_OCP_V3_2_PRSNT2_N_R";
61"P3V3_OCP_UV_2";
62"P3V3_OCP_UV_2_R1";
63"P3V3_OCP_2_EN_G";
64"P3V3_OCP_EN_2_R";
65"HP_LVC3_OCP_V3_2_EN";
66"P12V_OCP_UV_2";
67"P12V_OCP_UV_2_R";
68"P12V_OCP_2_EN_G";
69"OCP_V3_2_PRSNT0_R_N"CDS_PHYS_NET_NAME"OCP_V3_2_PRSNT0_R_N";
70"OCP_V3_2_PRSNT1_R_N"CDS_PHYS_NET_NAME"OCP_V3_2_PRSNT1_R_N";
71"P12V_OCP_EN_2_R";
72"OCP_V3_2_PRSNT3_R_N"CDS_PHYS_NET_NAME"OCP_V3_2_PRSNT3_R_N";
73"OCP_V3_2_PRSNT2_R_N"CDS_PHYS_NET_NAME"OCP_V3_2_PRSNT2_R_N";
%"GND"
"1","(-2975,-1300)","0","logical_power","I10";
;
HDL_POWER"GND"
CDS_LIB"logical_power"
SIZE"1B";
"A<SIZE-1..0>\NAC"14;
%"Q_CAP"
"1","(3550,400)","0","pure_quanta","I100";
;
PART_NUMBER"CH6223MEA03"
VALUE"22UF"
VOLTAGE"16V"
PACK_TYPE"C0805"
MATERIAL"X6S"
LOCATION"PC2141"
TOLERANCE"20%"
CDS_LIB"pure_quanta"
$SEC"1"
CDS_SEC"1";
"B"
$PN"2"34;
"A"
$PN"1"11;
%"GND"
"1","(3950,100)","0","logical_power","I101";
;
HDL_POWER"GND"
CDS_LIB"logical_power"
SIZE"1B";
"A<SIZE-1..0>\NAC"34;
%"Q_CAP"
"1","(3950,400)","0","pure_quanta","I102";
;
PART_NUMBER"CH6103KEA03"
MATERIAL"X6S"
PACK_TYPE"C0805"
VOLTAGE"16V"
VALUE"10UF"
LOCATION"PC2143"
TOLERANCE"10%"
CDS_LIB"pure_quanta"
$SEC"1"
CDS_SEC"1";
"B"
$PN"2"34;
"A"
$PN"1"11;
%"UNIVERSAL_POWER"
"1","(3950,700)","2","logical_power","I103";
;
HDL_POWER"P12V_OCP_V3_2"
CDS_LIB"logical_power";
"A"11;
%"GND"
"1","(3150,1825)","0","logical_power","I104";
;
HDL_POWER"GND"
SIZE"1B"
CDS_LIB"logical_power";
"A<SIZE-1..0>\NAC"35;
%"Q_CAP"
"1","(2375,2125)","0","pure_quanta","I105";
;
PART_NUMBER"CH31006KB18"
MATERIAL"EMPTY"
VALUE"0.01UF"
VOLTAGE"50V"
PACK_TYPE"C0402"
LOCATION"PC2149"
CDS_LIB"pure_quanta"
TOLERANCE"10%"
$SEC"1"
CDS_SEC"1";
"B"
$PN"2"48;
"A"
$PN"1"13;
%"Q_RES"
"2","(2650,2150)","0","pure_quanta","I106";
;
PART_NUMBER"CS61002FB02"
WATTAGE"1/16W"
VALUE"10M"
TOLERANCE"1%"
MATERIAL"CHIP"
PACK_TYPE"0402LF"
ROOM"NIC1_P3V3_BOM1"
LOCATION"PR4523"
CDS_LIB"pure_quanta"
$SEC"1"
CDS_SEC"1";
"A"
$PN"1"13;
"B"
$PN"2"48;
%"SCHOTTKY_AC"
"1","(2775,2750)","1","pure_quanta","I107";
;
PART_NUMBER"BC000340Z30"
VALUE"B340A-13-F"
LOCATION"PD109"
MATERIAL"IC"
PART_TYPE"SMLF"
NEEDS_NO_SIZE"TRUE"
CDS_LIB"pure_quanta"
CDS_LMAN_SYM_OUTLINE"-75,50,75,-50"
$SEC"1"
CDS_SEC"1";
"C"
$PN"C"13;
"A"
$PN"A"36;
%"Q_RES"
"2","(3400,2100)","0","pure_quanta","I108";
;
PART_NUMBER"CS41002FB09"
PACK_TYPE"0402LF"
MATERIAL"CHIP"
WATTAGE"1/16W"
VALUE"100K"
TOLERANCE"1%"
ROOM"NIC1_P3V3_BOM1"
LOCATION"R3833"
CDS_LIB"pure_quanta"
$SEC"1"
CDS_SEC"1";
"A"
$PN"1"12;
"B"
$PN"2"47;
%"Q_CAP"
"1","(3275,2725)","0","pure_quanta","I109";
;
PART_NUMBER"CH4104K1B00"
VOLTAGE"25V"
VALUE"0.1UF"
MATERIAL"X7R"
PACK_TYPE"0402"
LOCATION"PC2137"
CDS_LIB"pure_quanta"
TOLERANCE"10%"
$SEC"1"
CDS_SEC"1";
"B"
$PN"2"36;
"A"
$PN"1"13;
%"Q_RES"
"2","(-2550,-1450)","0","pure_quanta","I11";
;
PART_NUMBER"CS21002FB06"
VALUE"1K"
WATTAGE"1/16W"
TOLERANCE"1%"
MATERIAL"CHIP"
PACK_TYPE"0402LF"
LOCATION"R3133"
CDS_LIB"pure_quanta"
$SEC"1"
CDS_SEC"1";
"A"
$PN"1"4;
"B"
$PN"2"69;
%"Q_RES"
"2","(3800,2100)","0","pure_quanta","I110";
;
PART_NUMBER"CS41002FB09"
WATTAGE"1/16W"
MATERIAL"CHIP"
PACK_TYPE"0402LF"
TOLERANCE"1%"
VALUE"100K"
ROOM"NIC1_P3V3_BOM1"
LOCATION"R3826"
CDS_LIB"pure_quanta"
$SEC"1"
CDS_SEC"1";
"A"
$PN"1"12;
"B"
$PN"2"53;
%"VCCAUX15"
"1","(3600,2425)","0","logical_power","I111";
;
HDL_POWER"P3V3_AUX"
CDS_LIB"logical_power";
"A"12;
%"GND"
"1","(3850,2425)","0","logical_power","I112";
;
HDL_POWER"GND"
CDS_LIB"logical_power"
SIZE"1B";
"A<SIZE-1..0>\NAC"36;
%"Q_CAP"
"1","(3850,2725)","0","pure_quanta","I113";
;
PART_NUMBER"CH6103KEA01"
VOLTAGE"16V"
PACK_TYPE"C0805"
VALUE"10UF"
MATERIAL"X6S"
LOCATION"PC2142"
TOLERANCE"10%"
CDS_LIB"pure_quanta"
$SEC"1"
CDS_SEC"1";
"B"
$PN"2"36;
"A"
$PN"1"13;
%"UNIVERSAL_POWER"
"1","(3850,3025)","2","logical_power","I114";
;
HDL_POWER"P3V3_OCP_V3_2_R"
CDS_LIB"logical_power";
"A"13;
%"UNIVERSAL_POWER"
"1","(-2550,-1150)","0","logical_power","I12";
;
HDL_POWER"P3V3_AUX"
CDS_LIB"logical_power";
"A"4;
%"Q_RES"
"2","(-2325,-1450)","0","pure_quanta","I13";
;
PART_NUMBER"CS21002FB06"
WATTAGE"1/16W"
TOLERANCE"1%"
VALUE"1K"
MATERIAL"CHIP"
PACK_TYPE"0402LF"
LOCATION"R3135"
CDS_LIB"pure_quanta"
$SEC"1"
CDS_SEC"1";
"A"
$PN"1"4;
"B"
$PN"2"70;
%"Q_RES"
"2","(-2975,-350)","0","pure_quanta","I14";
;
PART_NUMBER"CS31002FB08"
PACK_TYPE"0402LF"
VALUE"10K"
TOLERANCE"1%"
MATERIAL"EMPTY"
WATTAGE"1/16W"
ROOM"NIC1_P12V_MAM_MAM_BOM1"
$LOCATION"R4065"
CDS_LIB"pure_quanta"
ROOM1"NIC1_P12V_MAM_TIC_BOM2"
CDS_LOCATION"R4065"
$SEC"1"
CDS_SEC"1";
"A"
$PN"1"5;
"B"
$PN"2"68;
%"UNIVERSAL_POWER"
"1","(-2975,-100)","0","logical_power","I15";
;
HDL_POWER"P12V_AUX"
CDS_LIB"logical_power";
"A"5;
%"MOSFET_NCH_DUAL"
"2","(-2350,-625)","0","pure_quanta","I16";
;
PART_NUMBER"BAM138K0003"
MATERIAL"EMPTY"
VALUE"PJT138K"
PART_TYPE"SMLF"
ROOM"NIC1_P12V_MAM_MAM_BOM1"
$LOCATION"Q118"
CDS_LIB"pure_quanta"
CDS_LMAN_SYM_OUTLINE"-150,150,150,-150"
NEEDS_NO_SIZE"TRUE"
ROOM1"NIC1_P12V_MAM_TIC_BOM2"
CDS_LOCATION"Q118"
$SEC"2"
CDS_SEC"2";
"S2"
$PN"4"15;
"G2"
$PN"5"68;
"D2"
$PN"3"67;
%"GND"
"1","(-2300,-925)","0","logical_power","I17";
;
HDL_POWER"GND"
SIZE"1B"
CDS_LIB"logical_power";
"A<SIZE-1..0>\NAC"15;
%"UNIVERSAL_GND"
"1","(-1575,-2950)","0","logical_power","I18";
;
HDL_POWER"GND"
CDS_LIB"logical_power";
"A"16;
%"74LVC2G07DW7"
"1","(-1175,-2650)","0","pure_quanta","I19";
;
PART_NUMBER"AL002G07003"
VALUE"74LVC2G07DW-7"
PART_TYPE"SMLF"
MATERIAL"IC"
LOCATION"U59"
NEEDS_NO_SIZE"TRUE"
CDS_LMAN_SYM_OUTLINE"-175,100,175,-100"
CDS_LIB"pure_quanta"
$SEC"1"
CDS_SEC"1";
"VCC"
$PN"5"6;
"GND"
$PN"2"16;
"2Y"
$PN"4"60;
"1Y"
$PN"6"60;
"2A"
$PN"3"72;
"1A"
$PN"1"73;
%"UNIVERSAL_GND"
"1","(-500,-3025)","0","logical_power","I20";
;
HDL_POWER"GND"
CDS_LIB"logical_power";
"A"17;
%"Q_CAP"
"1","(-500,-2825)","0","pure_quanta","I21";
;
PART_NUMBER"CH4104K1B00"
TOLERANCE"10%"
VALUE"0.1UF"
VOLTAGE"25V"
PACK_TYPE"0402"
MATERIAL"X7R"
$LOCATION"C1810"
CDS_LIB"pure_quanta"
CDS_LOCATION"C1810"
$SEC"1"
CDS_SEC"1";
"B"
$PN"2"17;
"A"
$PN"1"6;
%"UNIVERSAL_POWER"
"1","(-500,-2550)","0","logical_power","I22";
;
HDL_POWER"P3V3_AUX"
CDS_LIB"logical_power";
"A"6;
%"UNIVERSAL_GND"
"1","(-500,-2125)","0","logical_power","I23";
;
HDL_POWER"GND"
CDS_LIB"logical_power";
"A"18;
%"UNIVERSAL_GND"
"1","(-1575,-2025)","0","logical_power","I24";
;
HDL_POWER"GND"
CDS_LIB"logical_power";
"A"19;
%"74LVC2G07DW7"
"1","(-1175,-1750)","0","pure_quanta","I25";
;
PART_NUMBER"AL002G07003"
PART_TYPE"SMLF"
VALUE"74LVC2G07DW-7"
MATERIAL"IC"
LOCATION"U58"
NEEDS_NO_SIZE"TRUE"
CDS_LMAN_SYM_OUTLINE"-175,100,175,-100"
CDS_LIB"pure_quanta"
$SEC"1"
CDS_SEC"1";
"VCC"
$PN"5"7;
"GND"
$PN"2"19;
"2Y"
$PN"4"60;
"1Y"
$PN"6"60;
"2A"
$PN"3"70;
"1A"
$PN"1"69;
%"Q_CAP"
"1","(-500,-1925)","0","pure_quanta","I26";
;
PART_NUMBER"CH4104K1B00"
TOLERANCE"10%"
VOLTAGE"25V"
VALUE"0.1UF"
PACK_TYPE"0402"
MATERIAL"X7R"
$LOCATION"C1809"
CDS_LIB"pure_quanta"
CDS_LOCATION"C1809"
$SEC"1"
CDS_SEC"1";
"B"
$PN"2"18;
"A"
$PN"1"7;
%"UNIVERSAL_POWER"
"1","(-500,-1650)","0","logical_power","I27";
;
HDL_POWER"P3V3_AUX"
CDS_LIB"logical_power";
"A"7;
%"GND"
"1","(-175,-1300)","0","logical_power","I28";
;
HDL_POWER"GND"
SIZE"1B"
CDS_LIB"logical_power";
"A<SIZE-1..0>\NAC"20;
%"Q_RES"
"2","(-175,-1050)","0","pure_quanta","I29";
;
PART_NUMBER"CS31502FB05"
MATERIAL"EMPTY"
PACK_TYPE"0402LF"
VALUE"15K"
WATTAGE"1/16W"
TOLERANCE"1%"
ROOM"NIC1_P12V_MAM_MAM_BOM1"
LOCATION"PR3828"
CDS_LIB"pure_quanta"
ROOM1"NIC1_P12V_MAM_TIC_BOM2"
$SEC"1"
CDS_SEC"1";
"A"
$PN"1"41;
"B"
$PN"2"20;
%"Q_RES"
"2","(-2550,-2350)","0","pure_quanta","I3";
;
PART_NUMBER"CS21002FB06"
WATTAGE"1/16W"
TOLERANCE"1%"
VALUE"1K"
MATERIAL"CHIP"
PACK_TYPE"0402LF"
LOCATION"R3134"
CDS_LIB"pure_quanta"
$SEC"1"
CDS_SEC"1";
"A"
$PN"1"3;
"B"
$PN"2"73;
%"Q_RES"
"1","(-775,-425)","0","pure_quanta","I30";
;
PART_NUMBER"CS00002JB13"
WATTAGE"1/16W"
VALUE"0"
TOLERANCE"5%"
MATERIAL"EMPTY"
PACK_TYPE"0402LF"
ROOM"NIC1_P12V_MAM_MAM_BOM1"
$LOCATION"R3827"
CDS_LIB"pure_quanta"
ROOM1"NIC1_P12V_MAM_TIC_BOM2"
CDS_LOCATION"R3827"
$SEC"1"
CDS_SEC"1";
"B"
$PN"2"66;
"A"
$PN"1"67;
%"GND"
"1","(-750,-175)","0","logical_power","I31";
;
HDL_POWER"GND"
CDS_LIB"logical_power"
SIZE"1B";
"A<SIZE-1..0>\NAC"21;
%"Q_RES"
"2","(-175,-775)","0","pure_quanta","I32";
;
PART_NUMBER"CS26802FB02"
VALUE"6.8K"
TOLERANCE"1%"
WATTAGE"1/16W"
ROOM"NIC1_P12V_MAM_MAM_BOM1"
MATERIAL"EMPTY"
PACK_TYPE"0402LF"
LOCATION"PR3806"
CDS_LIB"pure_quanta"
ROOM1"NIC1_P12V_MAM_TIC_BOM2"
$SEC"1"
CDS_SEC"1";
"A"
$PN"1"66;
"B"
$PN"2"41;
%"Q_RES"
"2","(-175,-100)","0","pure_quanta","I33";
;
PART_NUMBER"CS41602FB05"
VALUE"160K"
WATTAGE"1/16W"
MATERIAL"EMPTY"
PACK_TYPE"0402LF"
TOLERANCE"1%"
ROOM"NIC1_P12V_MAM_MAM_BOM1"
LOCATION"PR3805"
CDS_LIB"pure_quanta"
ROOM1"NIC1_P12V_MAM_TIC_BOM2"
$SEC"1"
CDS_SEC"1";
"A"
$PN"1"9;
"B"
$PN"2"66;
%"Q_RES"
"1","(-3275,1300)","0","pure_quanta","I35";
;
PART_NUMBER"CS00002JB13"
VALUE"0"
TOLERANCE"5%"
PACK_TYPE"0402LF"
WATTAGE"1/16W"
MATERIAL"CHIP"
$LOCATION"R4060"
CDS_LIB"pure_quanta"
CDS_LOCATION"R4060"
$SEC"1"
CDS_SEC"1";
"B"
$PN"2"64;
"A"
$PN"1"65;
%"GND"
"1","(-2825,750)","0","logical_power","I36";
;
SIZE"1B"
CDS_LIB"logical_power"
HDL_POWER"GND";
"A<SIZE-1..0>\NAC"22;
%"Q_RES"
"2","(-2825,975)","0","pure_quanta","I37";
;
PART_NUMBER"CS24702JB10"
WATTAGE"1/16W"
MATERIAL"CHIP"
PACK_TYPE"0402LF"
TOLERANCE"5%"
VALUE"4.7K"
$LOCATION"R4066"
CDS_LIB"pure_quanta"
CDS_LOCATION"R4066"
$SEC"1"
CDS_SEC"1";
"A"
$PN"1"64;
"B"
$PN"2"22;
%"MOSFET_NCH_DUAL"
"1","(-2375,1350)","0","pure_quanta","I38";
;
PART_NUMBER"BAM138K0003"
PART_TYPE"SMLF"
VALUE"PJT138K"
MATERIAL"IC"
ROOM"NIC1_P3V3_BOM1"
$LOCATION"Q119"
NEEDS_NO_SIZE"TRUE"
CDS_LMAN_SYM_OUTLINE"-150,150,150,-150"
CDS_LIB"pure_quanta"
CDS_LOCATION"Q119"
$SEC"1"
CDS_SEC"1";
"D1"
$PN"6"63;
"G1"
$PN"2"64;
"S1"
$PN"1"23;
%"GND"
"1","(-2325,1000)","0","logical_power","I39";
;
CDS_LIB"logical_power"
SIZE"1B"
HDL_POWER"GND";
"A<SIZE-1..0>\NAC"23;
%"UNIVERSAL_POWER"
"1","(-2550,-2050)","0","logical_power","I4";
;
HDL_POWER"P3V3_AUX"
CDS_LIB"logical_power";
"A"3;
%"Q_RES"
"2","(-2325,1950)","0","pure_quanta","I40";
;
PART_NUMBER"CS31002FB08"
TOLERANCE"1%"
MATERIAL"CHIP"
PACK_TYPE"0402LF"
VALUE"10K"
WATTAGE"1/16W"
ROOM"NIC1_P3V3_BOM1"
$LOCATION"R4067"
CDS_LIB"pure_quanta"
CDS_LOCATION"R4067"
$SEC"1"
CDS_SEC"1";
"A"
$PN"1"8;
"B"
$PN"2"63;
%"UNIVERSAL_POWER"
"1","(-2325,2200)","0","logical_power","I41";
;
HDL_POWER"P12V_AUX"
CDS_LIB"logical_power";
"A"8;
%"MOSFET_NCH_DUAL"
"2","(-1600,1425)","0","pure_quanta","I42";
;
PART_NUMBER"BAM138K0003"
PART_TYPE"SMLF"
MATERIAL"IC"
VALUE"PJT138K"
ROOM"NIC1_P3V3_BOM1"
$LOCATION"Q119"
CDS_LIB"pure_quanta"
CDS_LMAN_SYM_OUTLINE"-150,150,150,-150"
NEEDS_NO_SIZE"TRUE"
CDS_LOCATION"Q119"
$SEC"2"
CDS_SEC"2";
"S2"
$PN"4"24;
"G2"
$PN"5"63;
"D2"
$PN"3"62;
%"GND"
"1","(-1550,1075)","0","logical_power","I43";
;
HDL_POWER"GND"
SIZE"1B"
CDS_LIB"logical_power";
"A<SIZE-1..0>\NAC"24;
%"DIODE_TVS"
"1","(-900,200)","1","pure_quanta","I44";
;
PART_NUMBER"BCSMF14AZ01"
MATERIAL"IC"
VALUE"SMF14A"
LOCATION"PD107"
CDS_LIB"pure_quanta"
CDS_LMAN_SYM_OUTLINE"-100,50,100,-50"
PART_TYPE"SMLF"
PIN_NAMES_ROTATE"True"
$SEC"1"
CDS_SEC"1";
"C"
$PN"C"
Pin_Length"Short"9;
"A"
$PN"A"21;
%"UNIVERSAL_POWER"
"1","(-750,550)","0","logical_power","I45";
;
HDL_POWER"P12V_AUX"
CDS_LIB"logical_power";
"A"9;
%"Q_CAP"
"1","(-525,200)","0","pure_quanta","I46";
;
PART_NUMBER"CH5104KEB02"
PACK_TYPE"C0402"
VALUE"1UF"
MATERIAL"X6S"
VOLTAGE"25V"
LOCATION"PC2139"
TOLERANCE"10%"
CDS_LIB"pure_quanta"
$SEC"1"
CDS_SEC"1";
"B"
$PN"2"21;
"A"
$PN"1"9;
%"Q_RES"
"1","(-550,1900)","0","pure_quanta","I47";
;
PART_NUMBER"CS00002JB13"
MATERIAL"CHIP"
WATTAGE"1/16W"
TOLERANCE"5%"
PACK_TYPE"0402LF"
VALUE"0"
ROOM"NIC1_P3V3_BOM1"
$LOCATION"R3807"
CDS_LIB"pure_quanta"
CDS_LOCATION"R3807"
$SEC"1"
CDS_SEC"1";
"B"
$PN"2"61;
"A"
$PN"1"62;
%"Q_RES"
"2","(-50,1275)","0","pure_quanta","I48";
;
PART_NUMBER"CS31502FB05"
WATTAGE"1/16W"
TOLERANCE"1%"
VALUE"15K"
PACK_TYPE"0402LF"
MATERIAL"CHIP"
ROOM"NIC1_P3V3_BOM1"
LOCATION"PR3812"
CDS_LIB"pure_quanta"
$SEC"1"
CDS_SEC"1";
"A"
$PN"1"56;
"B"
$PN"2"25;
%"GND"
"1","(-50,1025)","0","logical_power","I49";
;
HDL_POWER"GND"
SIZE"1B"
CDS_LIB"logical_power";
"A<SIZE-1..0>\NAC"25;
%"Q_RES"
"2","(-2325,-2350)","0","pure_quanta","I5";
;
PART_NUMBER"CS21002FB06"
PACK_TYPE"0402LF"
MATERIAL"CHIP"
WATTAGE"1/16W"
TOLERANCE"1%"
VALUE"1K"
LOCATION"R3136"
CDS_LIB"pure_quanta"
$SEC"1"
CDS_SEC"1";
"A"
$PN"1"3;
"B"
$PN"2"72;
%"Q_RES"
"2","(-50,1550)","0","pure_quanta","I50";
;
PART_NUMBER"CS27152FB03"
PACK_TYPE"0402LF"
MATERIAL"CHIP"
WATTAGE"1/16W"
TOLERANCE"1%"
VALUE"7.15K"
ROOM"NIC1_P3V3_BOM1"
LOCATION"PR3829"
CDS_LIB"pure_quanta"
$SEC"1"
CDS_SEC"1";
"A"
$PN"1"61;
"B"
$PN"2"56;
%"GND"
"1","(-400,2250)","0","logical_power","I51";
;
HDL_POWER"GND"
SIZE"1B"
CDS_LIB"logical_power";
"A<SIZE-1..0>\NAC"26;
%"Q_CAP"
"1","(-400,2525)","0","pure_quanta","I52";
;
PART_NUMBER"CH5104KEB02"
VOLTAGE"25V"
MATERIAL"X6S"
VALUE"1UF"
PACK_TYPE"C0402"
LOCATION"PC2140"
TOLERANCE"10%"
CDS_LIB"pure_quanta"
$SEC"1"
CDS_SEC"1";
"B"
$PN"2"26;
"A"
$PN"1"10;
%"Q_RES"
"2","(-50,2275)","0","pure_quanta","I53";
;
PART_NUMBER"CS32552FB06"
PACK_TYPE"0402LF"
MATERIAL"CHIP"
WATTAGE"1/16W"
TOLERANCE"1%"
VALUE"25.5K"
ROOM"NIC1_P3V3_BOM1"
LOCATION"PR3795"
CDS_LIB"pure_quanta"
$SEC"1"
CDS_SEC"1";
"A"
$PN"1"10;
"B"
$PN"2"61;
%"UNIVERSAL_POWER"
"1","(-400,2875)","0","logical_power","I54";
;
HDL_POWER"P3V3_AUX"
CDS_LIB"logical_power";
"A"10;
%"Q_RES"
"1","(375,-2475)","0","pure_quanta","I55";
;
PART_NUMBER"CS00002JB13"
MATERIAL"CHIP"
TOLERANCE"5%"
VALUE"0"
WATTAGE"1/16W"
PACK_TYPE"0402LF"
$LOCATION"R4753"
CDS_LIB"pure_quanta"
CDS_LOCATION"R4753"
$SEC"1"
CDS_SEC"1";
"B"
$PN"2"58;
"A"
$PN"1"60;
%"Q_RES"
"1","(425,-2150)","0","pure_quanta","I56";
;
PART_NUMBER"CS00002JB13"
TOLERANCE"5%"
PACK_TYPE"0402LF"
WATTAGE"1/16W"
MATERIAL"CHIP"
VALUE"0"
$LOCATION"R3143"
CDS_LIB"pure_quanta"
CDS_LOCATION"R3143"
$SEC"1"
CDS_SEC"1";
"B"
$PN"2"51;
"A"
$PN"1"60;
%"Q_RES"
"1","(400,-2300)","0","pure_quanta","I57";
;
PART_NUMBER"CS00002JB13"
TOLERANCE"5%"
PACK_TYPE"0402LF"
VALUE"0"
MATERIAL"CHIP"
WATTAGE"1/16W"
$LOCATION"R3142"
CDS_LIB"pure_quanta"
CDS_LOCATION"R3142"
$SEC"1"
CDS_SEC"1";
"B"
$PN"2"59;
"A"
$PN"1"60;
%"GND"
"1","(675,-1325)","0","logical_power","I58";
;
HDL_POWER"GND"
SIZE"1B"
CDS_LIB"logical_power";
"A<SIZE-1..0>\NAC"27;
%"Q_RES"
"2","(675,-1025)","0","pure_quanta","I59";
;
PART_NUMBER"CS33012FB03"
TOLERANCE"1%"
MATERIAL"EMPTY"
VALUE"30.1K"
WATTAGE"1/16W"
PACK_TYPE"0402LF"
ROOM"NIC1_P12V_MAM_MAM_BOM1"
LOCATION"PR3821"
CDS_LIB"pure_quanta"
ROOM1"NIC1_P12V_MAM_TIC_BOM2"
$SEC"1"
CDS_SEC"1";
"A"
$PN"1"40;
"B"
$PN"2"27;
%"Q_RES"
"1","(-3900,-1000)","0","pure_quanta","I6";
;
PART_NUMBER"CS00002JB13"
MATERIAL"EMPTY"
PACK_TYPE"0402LF"
WATTAGE"1/16W"
VALUE"0"
TOLERANCE"5%"
ROOM"NIC1_P12V_MAM_MAM_BOM1"
$LOCATION"R4059"
CDS_LIB"pure_quanta"
ROOM1"NIC1_P12V_MAM_TIC_BOM2"
CDS_LOCATION"R4059"
$SEC"1"
CDS_SEC"1";
"B"
$PN"2"71;
"A"
$PN"1"65;
%"GND"
"1","(150,-600)","0","logical_power","I60";
;
HDL_POWER"GND"
CDS_LIB"logical_power"
SIZE"1B";
"A<SIZE-1..0>\NAC"28;
%"Q_CAP"
"1","(150,-225)","0","pure_quanta","I61";
;
PART_NUMBER"CH5104KEB02"
VALUE"1UF"
MATERIAL"EMPTY"
VOLTAGE"25V"
PACK_TYPE"C0402"
ROOM"NIC1_P12V_MAM_MAM_BOM1"
LOCATION"PC2098"
TOLERANCE"10%"
CDS_LIB"pure_quanta"
ROOM1"NIC1_P12V_MAM_TIC_BOM2"
$SEC"1"
CDS_SEC"1";
"B"
$PN"2"28;
"A"
$PN"1"43;
%"Q_CAP"
"1","(375,-525)","1","pure_quanta","I62";
;
PART_NUMBER"CH5104KEB02"
VOLTAGE"25V"
VALUE"1UF"
PACK_TYPE"C0402"
ROOM"NIC1_P12V_MAM_MAM_BOM1"
LOCATION"PC2146"
MATERIAL"EMPTY"
TOLERANCE"10%"
CDS_LIB"pure_quanta"
ROOM1"NIC1_P12V_MAM_TIC_BOM2"
$SEC"1"
CDS_SEC"1";
"B"
$PN"2"42;
"A"
$PN"1"28;
%"MAX15090BEWIT"
"1","(1425,-525)","0","pure_quanta","I63";
;
PART_NUMBER"AL015080B00"
PART_TYPE"SMLF"
VALUE"MAX15090BEWI+T"
MATERIAL"EMPTY"
ROOM"NIC1_P12V_MAM_MAM_BOM1"
LOCATION"PU201"
CDS_LMAN_SYM_OUTLINE"-250,550,250,-550"
PIN_NAMES_ROTATE"True"
CDS_LIB"pure_quanta"
ROOM1"NIC1_P12V_MAM_TIC_BOM2"
$SEC"1"
CDS_SEC"1";
"PG"
$PN"D7"39;
"FAULT# \B"
$PN"C7"38;
"GND_C2"
$PN"C2"29;
"GND_C1"
$PN"C1"29;
"GND_B2"
$PN"B2"29;
"CDLY"
$PN"A7"29;
"GATE"
$PN"A6"49;
"OUT_D6"
$PN"D6"11;
"OUT_D4"
$PN"D4"11;
"OUT_C6"
$PN"C6"11;
"OUT_C4"
$PN"C4"11;
"OUT_B6"
$PN"B6"11;
"OUT_B4"
$PN"B4"11;
"OUT_A4"
$PN"A4"11;
"ISENSE"
$PN"A1"37;
"OV"
$PN"D3"41;
"UV"
$PN"D2"66;
"REG"
$PN"D1"42;
"EN# \B"
$PN"B7"27;
"CB"
$PN"B1"40;
"IN_D5"
$PN"D5"9;
"IN_C5"
$PN"C5"9;
"IN_C3"
$PN"C3"9;
"IN_B5"
$PN"B5"9;
"IN_B3"
$PN"B3"9;
"IN_A5"
$PN"A5"9;
"IN_A3"
$PN"A3"9;
"VCC"
$PN"A2"43;
%"Q_RES"
"2","(1675,-1875)","0","pure_quanta","I64";
;
PART_NUMBER"CS31002FB08"
TOLERANCE"1%"
VALUE"10K"
MATERIAL"CHIP"
WATTAGE"1/16W"
PACK_TYPE"0402LF"
$LOCATION"R3145"
CDS_LIB"pure_quanta"
CDS_LOCATION"R3145"
$SEC"1"
CDS_SEC"1";
"A"
$PN"1"1;
"B"
$PN"2"51;
%"UNIVERSAL_POWER"
"1","(1675,-1575)","0","logical_power","I65";
;
HDL_POWER"P3V3_AUX"
CDS_LIB"logical_power";
"A"1;
%"Q_RES"
"2","(1900,-1875)","0","pure_quanta","I66";
;
PART_NUMBER"CS31002FB08"
PACK_TYPE"0402LF"
VALUE"10K"
TOLERANCE"1%"
WATTAGE"1/16W"
MATERIAL"CHIP"
$LOCATION"R3147"
CDS_LIB"pure_quanta"
CDS_LOCATION"R3147"
$SEC"1"
CDS_SEC"1";
"A"
$PN"1"1;
"B"
$PN"2"59;
%"MOSFET_NCH_DUAL"
"1","(-3025,-950)","0","pure_quanta","I7";
;
PART_NUMBER"BAM138K0003"
PART_TYPE"SMLF"
MATERIAL"EMPTY"
VALUE"PJT138K"
ROOM"NIC1_P12V_MAM_MAM_BOM1"
$LOCATION"Q118"
CDS_LIB"pure_quanta"
CDS_LMAN_SYM_OUTLINE"-150,150,150,-150"
NEEDS_NO_SIZE"TRUE"
ROOM1"NIC1_P12V_MAM_TIC_BOM2"
CDS_LOCATION"Q118"
$SEC"1"
CDS_SEC"1";
"D1"
$PN"6"68;
"G1"
$PN"2"71;
"S1"
$PN"1"14;
%"Q_RES"
"2","(2250,-1900)","0","pure_quanta","I70";
;
PART_NUMBER"CS31002FB08"
MATERIAL"CHIP"
WATTAGE"1/16W"
TOLERANCE"1%"
VALUE"10K"
PACK_TYPE"0402LF"
$LOCATION"R4761"
CDS_LIB"pure_quanta"
CDS_LOCATION"R4761"
$SEC"1"
CDS_SEC"1";
"A"
$PN"1"1;
"B"
$PN"2"58;
%"GND"
"1","(2150,-1200)","0","logical_power","I71";
;
HDL_POWER"GND"
CDS_LIB"logical_power"
SIZE"1B";
"A<SIZE-1..0>\NAC"29;
%"Q_RES"
"2","(2275,-900)","0","pure_quanta","I72";
;
PART_NUMBER"CS18452FB01"
PACK_TYPE"0402LF"
MATERIAL"EMPTY"
VALUE"845"
TOLERANCE"1%"
WATTAGE"1/16W"
ROOM"NIC1_P12V_MAM_MAM_BOM1"
LOCATION"PR3823"
CDS_LIB"pure_quanta"
ROOM1"NIC1_P12V_MAM_TIC_BOM2"
$SEC"1"
CDS_SEC"1";
"A"
$PN"1"37;
"B"
$PN"2"29;
%"Q_CAP"
"1","(2250,-200)","0","pure_quanta","I73";
;
PART_NUMBER"CH31006KB18"
VOLTAGE"50V"
PACK_TYPE"C0402"
MATERIAL"EMPTY"
VALUE"0.01UF"
$LOCATION"C2148"
TOLERANCE"10%"
CDS_LIB"pure_quanta"
CDS_LOCATION"C2148"
$SEC"1"
CDS_SEC"1";
"B"
$PN"2"49;
"A"
$PN"1"11;
%"Q_RES"
"1","(3050,-850)","0","pure_quanta","I74";
;
PART_NUMBER"CS00002JB13"
TOLERANCE"5%"
VALUE"0"
PACK_TYPE"0402LF"
WATTAGE"1/16W"
MATERIAL"EMPTY"
$LOCATION"R3868"
CDS_LIB"pure_quanta"
ROOM1"NIC1_P12V_MAM_TIC_BOM2"
CDS_LOCATION"R3868"
$SEC"1"
CDS_SEC"1";
"B"
$PN"2"50;
"A"
$PN"1"37;
%"Q_RES"
"1","(3050,-725)","0","pure_quanta","I75";
;
PART_NUMBER"CS00002JB13"
WATTAGE"1/16W"
PACK_TYPE"0402LF"
TOLERANCE"5%"
VALUE"0"
MATERIAL"EMPTY"
ROOM"NIC1_P12V_MAM_MAM_BOM1"
$LOCATION"R3867"
CDS_LIB"pure_quanta"
CDS_LOCATION"R3867"
$SEC"1"
CDS_SEC"1";
"B"
$PN"2"57;
"A"
$PN"1"37;
%"Q_CAP"
"1","(2825,-425)","1","pure_quanta","I76";
;
PART_NUMBER"CH23906KB14"
VALUE"3900PF"
VOLTAGE"50V"
PACK_TYPE"C0402"
ROOM"NIC1_P12V_MAM_MAM_BOM1"
LOCATION"PC2150"
MATERIAL"EMPTY"
TOLERANCE"10%"
CDS_LIB"pure_quanta"
ROOM1"NIC1_P12V_MAM_TIC_BOM2"
$SEC"1"
CDS_SEC"1";
"B"
$PN"2"30;
"A"
$PN"1"49;
%"Q_RES"
"2","(2550,-200)","0","pure_quanta","I77";
;
PART_NUMBER"CS61002FB02"
VALUE"10M"
WATTAGE"1/16W"
PACK_TYPE"0402LF"
MATERIAL"EMPTY"
TOLERANCE"1%"
ROOM"NIC1_P12V_MAM_MAM_BOM1"
LOCATION"PR4522"
CDS_LIB"pure_quanta"
ROOM1"NIC1_P12V_MAM_TIC_BOM2"
$SEC"1"
CDS_SEC"1";
"A"
$PN"1"11;
"B"
$PN"2"49;
%"Q_RES"
"1","(2900,-525)","0","pure_quanta","I78";
;
PART_NUMBER"CS00002JB13"
PACK_TYPE"0402LF"
TOLERANCE"5%"
VALUE"0"
MATERIAL"EMPTY"
WATTAGE"1/16W"
ROOM"NIC1_P12V_MAM_MAM_BOM1"
$LOCATION"R3831"
CDS_LIB"pure_quanta"
ROOM1"NIC1_P12V_MAM_TIC_BOM2"
CDS_LOCATION"R3831"
$SEC"1"
CDS_SEC"1";
"B"
$PN"2"52;
"A"
$PN"1"39;
%"GND"
"1","(3000,-500)","0","logical_power","I79";
;
HDL_POWER"GND"
CDS_LIB"logical_power"
SIZE"1B";
"A<SIZE-1..0>\NAC"30;
%"Q_RES"
"2","(3250,-275)","0","pure_quanta","I80";
;
PART_NUMBER"CS41002FB09"
MATERIAL"EMPTY"
VALUE"100K"
TOLERANCE"1%"
WATTAGE"1/16W"
PACK_TYPE"0402LF"
ROOM"NIC1_P12V_MAM_MAM_BOM1"
LOCATION"R3816"
CDS_LIB"pure_quanta"
ROOM1"NIC1_P12V_MAM_TIC_BOM2"
$SEC"1"
CDS_SEC"1";
"A"
$PN"1"2;
"B"
$PN"2"38;
%"Q_RES"
"2","(3675,-275)","0","pure_quanta","I81";
;
PART_NUMBER"CS41002FB09"
TOLERANCE"1%"
VALUE"100K"
WATTAGE"1/16W"
PACK_TYPE"0402LF"
MATERIAL"EMPTY"
ROOM"NIC1_P12V_MAM_MAM_BOM1"
LOCATION"R3825"
CDS_LIB"pure_quanta"
ROOM1"NIC1_P12V_MAM_TIC_BOM2"
$SEC"1"
CDS_SEC"1";
"A"
$PN"1"2;
"B"
$PN"2"52;
%"Q_RES"
"2","(150,200)","0","pure_quanta","I85";
;
PART_NUMBER"CS01002FB07"
WATTAGE"1/16W"
PACK_TYPE"0402LF"
TOLERANCE"1%"
MATERIAL"EMPTY"
VALUE"10"
LOCATION"PR3830"
CDS_LIB"pure_quanta"
ROOM1"NIC1_P12V_MAM_TIC_BOM2"
ROOM"NIC1_P12V_MAM_MAM_BOM1"
$SEC"1"
CDS_SEC"1";
"A"
$PN"1"9;
"B"
$PN"2"43;
%"GND"
"1","(275,1725)","0","logical_power","I86";
;
HDL_POWER"GND"
CDS_LIB"logical_power"
SIZE"1B";
"A<SIZE-1..0>\NAC"31;
%"Q_CAP"
"1","(500,1800)","1","pure_quanta","I87";
;
PART_NUMBER"CH5104KEB02"
PACK_TYPE"C0402"
VALUE"1UF"
VOLTAGE"25V"
ROOM"NIC1_P3V3_BOM1"
LOCATION"PC2147"
TOLERANCE"10%"
CDS_LIB"pure_quanta"
MATERIAL"X6S"
$SEC"1"
CDS_SEC"1";
"B"
$PN"2"44;
"A"
$PN"1"31;
%"GND"
"1","(800,1000)","0","logical_power","I88";
;
HDL_POWER"GND"
CDS_LIB"logical_power"
SIZE"1B";
"A<SIZE-1..0>\NAC"32;
%"Q_RES"
"2","(800,1300)","0","pure_quanta","I89";
;
PART_NUMBER"CS25362FB02"
TOLERANCE"1%"
VALUE"5.36K"
MATERIAL"CHIP"
WATTAGE"1/16W"
PACK_TYPE"0402LF"
ROOM"NIC1_P3V3_BOM1"
LOCATION"PR3822"
CDS_LIB"pure_quanta"
$SEC"1"
CDS_SEC"1";
"A"
$PN"1"55;
"B"
$PN"2"32;
%"MAX15090BEWIT"
"1","(1550,1800)","0","pure_quanta","I90";
;
PART_NUMBER"AL015080B00"
MATERIAL"IC"
VALUE"MAX15090BEWI+T"
PART_TYPE"SMLF"
ROOM"NIC1_P3V3_BOM1"
LOCATION"PU200"
CDS_LIB"pure_quanta"
PIN_NAMES_ROTATE"True"
CDS_LMAN_SYM_OUTLINE"-250,550,250,-550"
$SEC"1"
CDS_SEC"1";
"PG"
$PN"D7"46;
"FAULT# \B"
$PN"C7"47;
"GND_C2"
$PN"C2"33;
"GND_C1"
$PN"C1"33;
"GND_B2"
$PN"B2"33;
"CDLY"
$PN"A7"33;
"GATE"
$PN"A6"48;
"OUT_D6"
$PN"D6"13;
"OUT_D4"
$PN"D4"13;
"OUT_C6"
$PN"C6"13;
"OUT_C4"
$PN"C4"13;
"OUT_B6"
$PN"B6"13;
"OUT_B4"
$PN"B4"13;
"OUT_A4"
$PN"A4"13;
"ISENSE"
$PN"A1"54;
"OV"
$PN"D3"56;
"UV"
$PN"D2"61;
"REG"
$PN"D1"44;
"EN# \B"
$PN"B7"32;
"CB"
$PN"B1"55;
"IN_D5"
$PN"D5"10;
"IN_C5"
$PN"C5"10;
"IN_C3"
$PN"C3"10;
"IN_B5"
$PN"B5"10;
"IN_B3"
$PN"B3"10;
"IN_A5"
$PN"A5"10;
"IN_A3"
$PN"A3"10;
"VCC"
$PN"A2"45;
%"Q_CAP"
"1","(275,2100)","0","pure_quanta","I91";
;
PART_NUMBER"CH5104KEB02"
PACK_TYPE"C0402"
VOLTAGE"25V"
MATERIAL"X6S"
VALUE"1UF"
ROOM"NIC1_P3V3_BOM1"
$LOCATION"PC190"
TOLERANCE"10%"
CDS_LIB"pure_quanta"
CDS_LOCATION"PC190"
$SEC"1"
CDS_SEC"1";
"B"
$PN"2"31;
"A"
$PN"1"45;
%"Q_RES"
"2","(275,2525)","0","pure_quanta","I92";
;
PART_NUMBER"CS01002FB07"
WATTAGE"1/16W"
MATERIAL"CHIP"
PACK_TYPE"0402LF"
TOLERANCE"1%"
VALUE"10"
ROOM"NIC1_P3V3_BOM1"
LOCATION"PR3782"
CDS_LIB"pure_quanta"
$SEC"1"
CDS_SEC"1";
"A"
$PN"1"10;
"B"
$PN"2"45;
%"SCHOTTKY_AC"
"1","(2650,425)","1","pure_quanta","I93";
;
PART_NUMBER"BC000340Z30"
MATERIAL"IC"
VALUE"B340A-13-F"
LOCATION"PD108"
PART_TYPE"SMLF"
NEEDS_NO_SIZE"TRUE"
CDS_LIB"pure_quanta"
CDS_LMAN_SYM_OUTLINE"-75,50,75,-50"
$SEC"1"
CDS_SEC"1";
"C"
$PN"C"11;
"A"
$PN"A"34;
%"GND"
"1","(2275,1125)","0","logical_power","I94";
;
HDL_POWER"GND"
CDS_LIB"logical_power"
SIZE"1B";
"A<SIZE-1..0>\NAC"33;
%"Q_RES"
"2","(2400,1450)","0","pure_quanta","I95";
;
PART_NUMBER"CS24532FB03"
TOLERANCE"1%"
MATERIAL"CHIP"
WATTAGE"1/16W"
PACK_TYPE"0402LF"
ROOM"NIC1_P3V3_BOM1"
VALUE"4.53K"
LOCATION"PR3824"
CDS_LIB"pure_quanta"
$SEC"1"
CDS_SEC"1";
"A"
$PN"1"54;
"B"
$PN"2"33;
%"Q_CAP"
"1","(2975,1900)","1","pure_quanta","I96";
;
PART_NUMBER"CH2686K1B01"
VALUE"6800PF"
VOLTAGE"50V"
PACK_TYPE"C0402"
ROOM"NIC1_P3V3_BOM1"
LOCATION"PC2151"
CDS_LIB"pure_quanta"
MATERIAL"X7R"
TOLERANCE"10%"
$SEC"1"
CDS_SEC"1";
"B"
$PN"2"35;
"A"
$PN"1"48;
%"Q_RES"
"1","(3050,1800)","0","pure_quanta","I97";
;
PART_NUMBER"CS00002JB13"
PACK_TYPE"0402LF"
MATERIAL"CHIP"
TOLERANCE"5%"
VALUE"0"
WATTAGE"1/16W"
ROOM"NIC1_P3V3_BOM1"
LOCATION"R3832"
CDS_LIB"pure_quanta"
$SEC"1"
CDS_SEC"1";
"B"
$PN"2"53;
"A"
$PN"1"46;
%"Q_CAP"
"1","(3125,400)","0","pure_quanta","I98";
;
PART_NUMBER"CH4104K1B00"
VALUE"0.1UF"
MATERIAL"X7R"
PACK_TYPE"0402"
VOLTAGE"25V"
LOCATION"PC2152"
TOLERANCE"10%"
CDS_LIB"pure_quanta"
$SEC"1"
CDS_SEC"1";
"B"
$PN"2"34;
"A"
$PN"1"11;
%"VCCAUX15"
"1","(3450,75)","0","logical_power","I99";
;
HDL_POWER"P3V3_AUX"
CDS_LIB"logical_power";
"A"2;
END.
